<schema xmlns="http://www.cadence.com/spb/csschema"
	xmlns:xsi="http://www.w3.org/2001/XMLSchema-instance"
	xsi:schemaLocation="http://www.cadence.com/spb/csschema CSSchema002.xsd">
  <header>
    <schemaVersion>16.5</schemaVersion>
    <creatorTool>conceptHDL</creatorTool>
    <modifierTool>conceptHDL</modifierTool>
    <modificationTime>2011-10-25T14:25:03</modificationTime>
    <savedLibrary>mstr_symbols</savedLibrary>
  </header>
  <designs>
    <design schemaType="nameBased" name="p3v3" view="sch_1">
      <lastids>
        <netid>4</netid>
      </lastids>
      <cells>
      </cells>
      <nets>
        <net>
          <id>N1</id>
          <name>g</name>
          <scope>interface</scope>
          <direction>inout</direction>
        </net>
        <net>
          <id>N2</id>
          <name>page1_g</name>
        </net>
        <net>
          <id>N4</id>
          <name>page1_p3v3</name>
        </net>
        <net>
          <id>N3</id>
          <name>p3v3</name>
          <scope>global</scope>
        </net>
      </nets>
      <aliases>
        <alias net1="N2" lsb1="-1" msb1="-1" net2="N1" lsb2="-1" msb2="-1" />
        <alias net1="N4" lsb1="-1" msb1="-1" net2="N2" lsb2="-1" msb2="-1" />
        <alias net1="N4" lsb1="-1" msb1="-1" net2="N3" lsb2="-1" msb2="-1" />
      </aliases>
      <differentialnets>
      </differentialnets>
      <differentialbusnets>
      </differentialbusnets>
      <netgroups>
      </netgroups>
      <netinterfaces>
      </netinterfaces>
      <instances>
      </instances>
      <templateresolutions>
      </templateresolutions>
      <templateinstances>
      </templateinstances>
      <extensions>
        <extension name="schematic_extension">
        <schematicExtension>
        <netScopes>
          <netScope ref="g">
            <pageScope number="1">
              <scope>interface</scope>
              <direction>unknown</direction>
            </pageScope>
          </netScope>
          <netScope ref="p3v3">
            <pageScope number="1">
              <scope>global</scope>
            </pageScope>
          </netScope>
        </netScopes>
        <pages>
          <page number="1">
            <physicalPageNumber>1</physicalPageNumber>
            <errorStatus>false</errorStatus>
            <nets>
              <net ref="g"></net>
              <net ref="p3v3"></net>
            </nets>
            <instances>
            </instances>
          </page>
        </pages>
      </schematicExtension>
        </extension>
      </extensions>
    </design>
  </designs>
</schema>
